(kicad_pcb
	(version 20260206)
	(generator "pcbnew")
	(generator_version "10.0")
	(general
		(thickness 1.6)
		(legacy_teardrops no)
	)
	(paper "A4")
	(title_block
		(title "Bryce Canyon_R.DPB_16317-1_OCP.brd")
		(comment 1 "Bryce Canyon / footprints 1272-1275 of 2099")
	)
	(layers
		(0 "F.Cu" signal "TOP")
		(4 "In1.Cu" signal "L2GND")
		(6 "In2.Cu" signal "L3")
		(8 "In3.Cu" signal "L4VCC")
		(10 "In4.Cu" signal "L5VCC")
		(12 "In5.Cu" signal "L6")
		(14 "In6.Cu" signal "L7GND")
		(2 "B.Cu" signal "BOTTOM")
		(9 "F.Adhes" user "F.Adhesive")
		(11 "B.Adhes" user "B.Adhesive")
		(13 "F.Paste" user "Package Geometry/Pastemask Top")
		(15 "B.Paste" user "Package Geometry/Pastemask Bottom")
		(5 "F.SilkS" user "Ref Des/Silkscreen Top")
		(7 "B.SilkS" user "Ref Des/Silkscreen Bottom")
		(1 "F.Mask" user "Board Geometry/Soldermask Top")
		(3 "B.Mask" user "Board Geometry/Soldermask Bottom")
		(17 "Dwgs.User" user "User.Drawings")
		(19 "Cmts.User" user "User.Comments")
		(21 "Eco1.User" user "User.Eco1")
		(23 "Eco2.User" user "User.Eco2")
		(25 "Edge.Cuts" user "Board Geometry/Outline")
		(27 "Margin" user)
		(31 "F.CrtYd" user "Package Geometry/Place Bound Top")
		(29 "B.CrtYd" user "Package Geometry/Place Bound Bottom")
		(35 "F.Fab" user "Ref Des/Assembly Top")
		(33 "B.Fab" user "Ref Des/Assembly Bottom")
	)
	(footprint ""
		(layer "F.Cu")
		(at 325.550022 -28.910026 -90)
		(property "Reference" "HDDSAS30"
			(at 0 0 270)
			(layer "F.SilkS")
			(hide yes)
			(effects
				(font
					(size 1.27 1.27)
				)
			)
		)
		(property "Value" "SKT-SAS15P-14P-45-GP"
			(at -20.7645 -8.9789 270)
			(unlocked yes)
			(layer "F.Fab")
			(hide yes)
			(effects
				(font
					(size 1.016 1.016)
					(thickness 0.1524)
				)
			)
		)
		(property "Device Type" "10120818-001C-TRLF"
			(at -20.7645 -10.5029 270)
			(unlocked yes)
			(layer "F.Fab")
			(hide yes)
			(effects
				(font
					(size 1.016 1.016)
					(thickness 0.1524)
				)
			)
		)
		(duplicate_pad_numbers_are_jumpers no)
		(fp_line
			(start 1.651 4.2926)
			(end 1.651 3.0099)
			(stroke
				(width 0.1524)
				(type default)
			)
			(layer "F.SilkS")
		)
		(fp_line
			(start 8.509 4.2926)
			(end 1.651 4.2926)
			(stroke
				(width 0.1524)
				(type default)
			)
			(layer "F.SilkS")
		)
		(fp_line
			(start -23.4188 3.0099)
			(end -23.4188 -3.2512)
			(stroke
				(width 0.1524)
				(type default)
			)
			(layer "F.SilkS")
		)
		(fp_line
			(start 1.651 3.0099)
			(end -23.4188 3.0099)
			(stroke
				(width 0.1524)
				(type default)
			)
			(layer "F.SilkS")
		)
		(fp_line
			(start 8.509 3.0099)
			(end 8.509 4.2926)
			(stroke
				(width 0.1524)
				(type default)
			)
			(layer "F.SilkS")
		)
		(fp_line
			(start 23.4188 3.0099)
			(end 8.509 3.0099)
			(stroke
				(width 0.1524)
				(type default)
			)
			(layer "F.SilkS")
		)
		(fp_line
			(start -23.4188 -3.2512)
			(end 23.4188 -3.2512)
			(stroke
				(width 0.1524)
				(type default)
			)
			(layer "F.SilkS")
		)
		(fp_line
			(start 23.4188 -3.2512)
			(end 23.4188 3.0099)
			(stroke
				(width 0.1524)
				(type default)
			)
			(layer "F.SilkS")
		)
		(fp_line
			(start 15.5067 -3.3401)
			(end 16.2687 -3.3401)
			(stroke
				(width 0.3302)
				(type default)
			)
			(layer "F.SilkS")
		)
		(fp_poly
			(pts
				(xy 15.868904 -3.230372) (xy 16.503904 -3.865372) (xy 15.233904 -3.865372)
			)
			(stroke
				(width 0)
				(type default)
			)
			(fill yes)
			(layer "F.SilkS")
		)
		(fp_poly
			(pts
				(xy -22.8727 -2.7559) (xy 22.8727 -2.7559) (xy 22.8727 2.7559) (xy 8.255 2.7559) (xy 8.255 3.5179)
				(xy 1.905 3.5179) (xy 1.905 2.7559) (xy -22.8727 2.7559)
			)
			(stroke
				(width 0)
				(type default)
			)
			(fill no)
			(layer "F.CrtYd")
		)
		(fp_poly
			(pts
				(xy 1.397 4.5466) (xy 1.397 3.2639) (xy -23.6728 3.2639) (xy -23.6728 -3.5052) (xy 23.6728 -3.5052)
				(xy 23.6728 -0.00635) (xy 22.8727 -0.00635) (xy 22.8727 -2.7559) (xy -22.8727 -2.7559) (xy -22.8727 2.7559)
				(xy 1.905 2.7559) (xy 1.905 3.5179) (xy 8.255 3.5179) (xy 8.255 2.7559) (xy 22.8727 2.7559) (xy 22.8727 0.00635)
				(xy 23.6728 0.00635) (xy 23.6728 3.2639) (xy 8.763 3.2639) (xy 8.763 4.5466)
			)
			(stroke
				(width 0)
				(type default)
			)
			(fill no)
			(layer "F.CrtYd")
		)
		(fp_poly
			(pts
				(xy 1.397 4.5466) (xy 1.397 3.2639) (xy -23.6728 3.2639) (xy -23.6728 -3.5052) (xy 23.6728 -3.5052)
				(xy 23.6728 3.2639) (xy 8.763 3.2639) (xy 8.763 4.5466)
			)
			(stroke
				(width 0)
				(type default)
			)
			(fill no)
			(layer "F.Fab")
		)
		(pad "" np_thru_hole circle
			(at -18.874994 0 270)
			(size 0.254 0.254)
			(drill 1.3462)
			(layers "*.Cu" "*.Mask")
			(clearance 0.9017)
			(thermal_gap 0.9017)
		)
		(pad "" np_thru_hole circle
			(at 18.874994 0 270)
			(size 0.254 0.254)
			(drill 0.9398)
			(layers "*.Cu" "*.Mask")
			(clearance 0.6985)
			(thermal_gap 0.6985)
		)
		(pad "G1" smd rect
			(at 21.874988 0 270)
			(size 2.5908 2.5908)
			(layers "F.Cu" "F.Mask" "F.Paste")
			(net "GND")
		)
		(pad "G2" smd rect
			(at -21.874988 0 270)
			(size 2.5908 2.5908)
			(layers "F.Cu" "F.Mask" "F.Paste")
			(net "GND")
		)
		(pad "P1" smd rect
			(at 1.905 -1.82499 270)
			(size 0.6096 2.3622)
			(layers "F.Cu" "F.Mask" "F.Paste")
			(net "Net_1644")
		)
		(pad "P2" smd rect
			(at 0.635 -1.82499 270)
			(size 0.6096 2.3622)
			(layers "F.Cu" "F.Mask" "F.Paste")
			(net "Net_1645")
		)
		(pad "P3" smd rect
			(at -0.635 -1.82499 270)
			(size 0.6096 2.3622)
			(layers "F.Cu" "F.Mask" "F.Paste")
			(net "Net_1646")
		)
		(pad "P4" smd rect
			(at -1.905 -1.82499 270)
			(size 0.6096 2.3622)
			(layers "F.Cu" "F.Mask" "F.Paste")
			(net "GND")
		)
		(pad "P5" smd rect
			(at -3.175 -1.82499 270)
			(size 0.6096 2.3622)
			(layers "F.Cu" "F.Mask" "F.Paste")
			(net "HDD_PRSNT_30")
		)
		(pad "P6" smd rect
			(at -4.445 -1.82499 270)
			(size 0.6096 2.3622)
			(layers "F.Cu" "F.Mask" "F.Paste")
			(net "GND")
		)
		(pad "P7" smd rect
			(at -5.715 -1.82499 270)
			(size 0.6096 2.3622)
			(layers "F.Cu" "F.Mask" "F.Paste")
			(net "5V_PRE_30")
		)
		(pad "P8" smd rect
			(at -6.985 -1.82499 270)
			(size 0.6096 2.3622)
			(layers "F.Cu" "F.Mask" "F.Paste")
			(net "P5V_HDD30")
		)
		(pad "P9" smd rect
			(at -8.255 -1.82499 270)
			(size 0.6096 2.3622)
			(layers "F.Cu" "F.Mask" "F.Paste")
			(net "P5V_HDD30")
		)
		(pad "P10" smd rect
			(at -9.525 -1.82499 270)
			(size 0.6096 2.3622)
			(layers "F.Cu" "F.Mask" "F.Paste")
			(net "GND")
		)
		(pad "P11" smd rect
			(at -10.795 -1.82499 270)
			(size 0.6096 2.3622)
			(layers "F.Cu" "F.Mask" "F.Paste")
			(net "ACT_HDD_30")
		)
		(pad "P12" smd rect
			(at -12.065 -1.82499 270)
			(size 0.6096 2.3622)
			(layers "F.Cu" "F.Mask" "F.Paste")
			(net "GND")
		)
		(pad "P13" smd rect
			(at -13.335 -1.82499 270)
			(size 0.6096 2.3622)
			(layers "F.Cu" "F.Mask" "F.Paste")
			(net "12V_PRE_30")
		)
		(pad "P14" smd rect
			(at -14.605 -1.82499 270)
			(size 0.6096 2.3622)
			(layers "F.Cu" "F.Mask" "F.Paste")
			(net "P12V_HDD30")
		)
		(pad "P15" smd rect
			(at -15.875 -1.82499 270)
			(size 0.6096 2.3622)
			(layers "F.Cu" "F.Mask" "F.Paste")
			(net "P12V_HDD30")
		)
		(pad "S1" smd rect
			(at 15.875 -1.82499 270)
			(size 0.6096 2.3622)
			(layers "F.Cu" "F.Mask" "F.Paste")
			(net "GND")
		)
		(pad "S2" smd rect
			(at 14.605 -1.82499 270)
			(size 0.6096 2.3622)
			(layers "F.Cu" "F.Mask" "F.Paste")
			(net "SAS_HDD_RX_P30")
		)
		(pad "S3" smd rect
			(at 13.335 -1.82499 270)
			(size 0.6096 2.3622)
			(layers "F.Cu" "F.Mask" "F.Paste")
			(net "SAS_HDD_RX_N30")
		)
		(pad "S4" smd rect
			(at 12.065 -1.82499 270)
			(size 0.6096 2.3622)
			(layers "F.Cu" "F.Mask" "F.Paste")
			(net "GND")
		)
		(pad "S5" smd rect
			(at 10.795 -1.82499 270)
			(size 0.6096 2.3622)
			(layers "F.Cu" "F.Mask" "F.Paste")
			(net "PHY_DRV_B_TO_SCC_B_30_DN")
		)
		(pad "S6" smd rect
			(at 9.525 -1.82499 270)
			(size 0.6096 2.3622)
			(layers "F.Cu" "F.Mask" "F.Paste")
			(net "PHY_DRV_B_TO_SCC_B_30_DP")
		)
		(pad "S7" smd rect
			(at 8.255 -1.82499 270)
			(size 0.6096 2.3622)
			(layers "F.Cu" "F.Mask" "F.Paste")
			(net "GND")
		)
		(pad "S8" smd rect
			(at 7.480046 2.845054 270)
			(size 0.508 2.3622)
			(layers "F.Cu" "F.Mask" "F.Paste")
			(net "GND")
		)
		(pad "S9" smd rect
			(at 6.679946 2.845054 270)
			(size 0.508 2.3622)
			(layers "F.Cu" "F.Mask" "F.Paste")
			(net "Net_455")
		)
		(pad "S10" smd rect
			(at 5.8801 2.845054 270)
			(size 0.508 2.3622)
			(layers "F.Cu" "F.Mask" "F.Paste")
			(net "Net_347")
		)
		(pad "S11" smd rect
			(at 5.08 2.845054 270)
			(size 0.508 2.3622)
			(layers "F.Cu" "F.Mask" "F.Paste")
			(net "GND")
		)
		(pad "S12" smd rect
			(at 4.2799 2.845054 270)
			(size 0.508 2.3622)
			(layers "F.Cu" "F.Mask" "F.Paste")
			(net "Net_383")
		)
		(pad "S13" smd rect
			(at 3.480054 2.845054 270)
			(size 0.508 2.3622)
			(layers "F.Cu" "F.Mask" "F.Paste")
			(net "Net_419")
		)
		(pad "S14" smd rect
			(at 2.679954 2.845054 270)
			(size 0.508 2.3622)
			(layers "F.Cu" "F.Mask" "F.Paste")
			(net "GND")
		)
		(zone
			(layer "F.Cu")
			(hatch none 0.5)
			(connect_pads
				(clearance 0)
			)
			(min_thickness 0.25)
			(keepout
				(tracks allowed)
				(vias not_allowed)
				(pads allowed)
				(copperpour not_allowed)
				(footprints allowed)
			)
			(placement
				(enabled no)
				(sheetname "")
			)
			(fill
				(thermal_gap 0.5)
				(thermal_bridge_width 0.5)
				(island_removal_mode 0)
			)
			(polygon
				(pts
					(xy 329.207622 -45.648626) (xy 322.133722 -45.648626) (xy 322.133722 -52.582826) (xy 323.238622 -52.582826)
					(xy 323.238622 -48.468026) (xy 327.861422 -48.468026) (xy 327.861422 -52.582826) (xy 329.207622 -52.582826)
				)
			)
		)
		(zone
			(layer "F.Cu")
			(hatch none 0.5)
			(connect_pads
				(clearance 0)
			)
			(min_thickness 0.25)
			(keepout
				(tracks not_allowed)
				(vias allowed)
				(pads allowed)
				(copperpour not_allowed)
				(footprints allowed)
			)
			(placement
				(enabled no)
				(sheetname "")
			)
			(fill
				(thermal_gap 0.5)
				(thermal_bridge_width 0.5)
				(island_removal_mode 0)
			)
			(polygon
				(pts
					(xy 329.207622 -45.648626) (xy 322.133722 -45.648626) (xy 322.133722 -52.582826) (xy 323.238622 -52.582826)
					(xy 323.238622 -48.468026) (xy 327.861422 -48.468026) (xy 327.861422 -52.582826) (xy 329.207622 -52.582826)
				)
			)
		)
		(zone
			(layer "F.Cu")
			(hatch none 0.5)
			(connect_pads
				(clearance 0)
			)
			(min_thickness 0.25)
			(keepout
				(tracks not_allowed)
				(vias allowed)
				(pads allowed)
				(copperpour not_allowed)
				(footprints allowed)
			)
			(placement
				(enabled no)
				(sheetname "")
			)
			(fill
				(thermal_gap 0.5)
				(thermal_bridge_width 0.5)
				(island_removal_mode 0)
			)
			(polygon
				(pts
					(xy 329.207622 -12.171426) (xy 322.133722 -12.171426) (xy 322.133722 -5.237226) (xy 323.238622 -5.237226)
					(xy 323.238622 -9.352026) (xy 327.861422 -9.352026) (xy 327.861422 -5.237226) (xy 329.207622 -5.237226)
				)
			)
		)
		(zone
			(layer "F.Cu")
			(hatch none 0.5)
			(connect_pads
				(clearance 0)
			)
			(min_thickness 0.25)
			(keepout
				(tracks allowed)
				(vias not_allowed)
				(pads allowed)
				(copperpour not_allowed)
				(footprints allowed)
			)
			(placement
				(enabled no)
				(sheetname "")
			)
			(fill
				(thermal_gap 0.5)
				(thermal_bridge_width 0.5)
				(island_removal_mode 0)
			)
			(polygon
				(pts
					(xy 329.207622 -12.171426) (xy 322.133722 -12.171426) (xy 322.133722 -5.237226) (xy 323.238622 -5.237226)
					(xy 323.238622 -9.352026) (xy 327.861422 -9.352026) (xy 327.861422 -5.237226) (xy 329.207622 -5.237226)
				)
			)
		)
		(zone
			(layers "F.Cu" "B.Cu" "In1.Cu" "In2.Cu" "In3.Cu" "In4.Cu" "In5.Cu" "In6.Cu")
			(hatch none 0.5)
			(connect_pads
				(clearance 0)
			)
			(min_thickness 0.25)
			(keepout
				(tracks not_allowed)
				(vias allowed)
				(pads allowed)
				(copperpour not_allowed)
				(footprints allowed)
			)
			(placement
				(enabled no)
				(sheetname "")
			)
			(fill
				(thermal_gap 0.5)
				(thermal_bridge_width 0.5)
				(island_removal_mode 0)
			)
			(polygon
				(pts
					(arc
						(start 326.324722 -10.035032)
						(mid 324.775322 -10.035032)
						(end 326.324722 -10.035032)
					)
				)
			)
		)
		(zone
			(layers "F.Cu" "B.Cu" "In1.Cu" "In2.Cu" "In3.Cu" "In4.Cu" "In5.Cu" "In6.Cu")
			(hatch none 0.5)
			(connect_pads
				(clearance 0)
			)
			(min_thickness 0.25)
			(keepout
				(tracks not_allowed)
				(vias allowed)
				(pads allowed)
				(copperpour not_allowed)
				(footprints allowed)
			)
			(placement
				(enabled no)
				(sheetname "")
			)
			(fill
				(thermal_gap 0.5)
				(thermal_bridge_width 0.5)
				(island_removal_mode 0)
			)
			(polygon
				(pts
					(arc
						(start 326.527922 -47.78502)
						(mid 324.572122 -47.78502)
						(end 326.527922 -47.78502)
					)
				)
			)
		)
	)
	(footprint ""
		(layer "F.Cu")
		(at 146.431 -148.717 -90)
		(property "Reference" "C238"
			(at 0 0 270)
			(layer "F.SilkS")
			(hide yes)
			(effects
				(font
					(size 1.27 1.27)
				)
			)
		)
		(property "Value" "SC1U16V3KX-5GP"
			(at 0 -2.8194 270)
			(unlocked yes)
			(layer "F.Fab")
			(hide yes)
			(effects
				(font
					(size 1.016 1.016)
					(thickness 0.1524)
				)
			)
		)
		(property "Device Type" "C603H36"
			(at 0 -4.3434 270)
			(unlocked yes)
			(layer "F.Fab")
			(hide yes)
			(effects
				(font
					(size 1.016 1.016)
					(thickness 0.1524)
				)
			)
		)
		(duplicate_pad_numbers_are_jumpers no)
		(fp_line
			(start 0.508 0)
			(end -0.508 0)
			(stroke
				(width 0.2032)
				(type default)
			)
			(layer "F.SilkS")
		)
		(fp_rect
			(start -0.5842 1.3335)
			(end 0.5842 -1.3335)
			(stroke
				(width 0)
				(type default)
			)
			(fill no)
			(layer "F.CrtYd")
		)
		(fp_rect
			(start -0.5842 1.3335)
			(end 0.5842 -1.3335)
			(stroke
				(width 0)
				(type default)
			)
			(fill no)
			(layer "F.Fab")
		)
		(pad "1" smd custom
			(at 0 -0.762 270)
			(size 0.2159 0.2159)
			(layers "F.Cu" "F.Mask" "F.Paste")
			(net "P5V_HDD16")
			(options
				(clearance outline)
				(anchor circle)
			)
			(primitives
				(gr_poly
					(pts
						(arc
							(start -0.3302 -0.4318)
							(mid -0.402042 -0.402042)
							(end -0.4318 -0.3302)
						)
						(arc
							(start -0.4318 0.3302)
							(mid -0.402042 0.402042)
							(end -0.3302 0.4318)
						)
						(arc
							(start 0.3302 0.4318)
							(mid 0.402042 0.402042)
							(end 0.4318 0.3302)
						)
						(arc
							(start 0.4318 -0.3302)
							(mid 0.402042 -0.402042)
							(end 0.3302 -0.4318)
						)
					)
					(width 0)
					(fill yes)
				)
			)
		)
		(pad "2" smd custom
			(at 0 0.762 270)
			(size 0.2159 0.2159)
			(layers "F.Cu" "F.Mask" "F.Paste")
			(net "GND")
			(options
				(clearance outline)
				(anchor circle)
			)
			(primitives
				(gr_poly
					(pts
						(arc
							(start -0.3302 -0.4318)
							(mid -0.402042 -0.402042)
							(end -0.4318 -0.3302)
						)
						(arc
							(start -0.4318 0.3302)
							(mid -0.402042 0.402042)
							(end -0.3302 0.4318)
						)
						(arc
							(start 0.3302 0.4318)
							(mid 0.402042 0.402042)
							(end 0.4318 0.3302)
						)
						(arc
							(start 0.4318 -0.3302)
							(mid 0.402042 -0.402042)
							(end 0.3302 -0.4318)
						)
					)
					(width 0)
					(fill yes)
				)
			)
		)
	)
	(footprint ""
		(layer "F.Cu")
		(at 333.629 -270.5862 -90)
		(property "Reference" "R256"
			(at 0 0 270)
			(layer "F.SilkS")
			(hide yes)
			(effects
				(font
					(size 1.27 1.27)
				)
			)
		)
		(property "Value" "2R6F-GP"
			(at -0.0508 -4.8514 270)
			(unlocked yes)
			(layer "F.Fab")
			(hide yes)
			(effects
				(font
					(size 1.016 1.016)
					(thickness 0.1524)
				)
			)
		)
		(property "Device Type" "R1206H26"
			(at 0 -6.3754 270)
			(unlocked yes)
			(layer "F.Fab")
			(hide yes)
			(effects
				(font
					(size 1.016 1.016)
					(thickness 0.1524)
				)
			)
		)
		(duplicate_pad_numbers_are_jumpers no)
		(fp_line
			(start -1.016 2.2352)
			(end -1.016 -2.2352)
			(stroke
				(width 0.1524)
				(type default)
			)
			(layer "F.SilkS")
		)
		(fp_line
			(start 1.016 2.2352)
			(end -1.016 2.2352)
			(stroke
				(width 0.1524)
				(type default)
			)
			(layer "F.SilkS")
		)
		(fp_line
			(start -1.016 -2.2352)
			(end 1.016 -2.2352)
			(stroke
				(width 0.1524)
				(type default)
			)
			(layer "F.SilkS")
		)
		(fp_line
			(start 1.016 -2.2352)
			(end 1.016 2.2352)
			(stroke
				(width 0.1524)
				(type default)
			)
			(layer "F.SilkS")
		)
		(fp_rect
			(start -1.0922 2.3114)
			(end 1.0922 -2.3114)
			(stroke
				(width 0)
				(type default)
			)
			(fill no)
			(layer "F.CrtYd")
		)
		(fp_poly
			(pts
				(xy -1.0922 -2.3114) (xy 1.0922 -2.3114) (xy 1.0922 2.3114) (xy -1.0922 2.3114)
			)
			(stroke
				(width 0)
				(type default)
			)
			(fill no)
			(layer "F.Fab")
		)
		(pad "1" smd rect
			(at 0 -1.397 270)
			(size 1.651 1.27)
			(layers "F.Cu" "F.Mask" "F.Paste")
			(net "P12V_HDD6")
		)
		(pad "2" smd rect
			(at 0 1.397 270)
			(size 1.651 1.27)
			(layers "F.Cu" "F.Mask" "F.Paste")
			(net "12V_PRE_6")
		)
	)
	(footprint ""
		(layer "F.Cu")
		(at 158.663386 -129.66065 90)
		(property "Reference" "C237"
			(at 0 0 90)
			(layer "F.SilkS")
			(hide yes)
			(effects
				(font
					(size 1.27 1.27)
				)
			)
		)
		(property "Value" "SCD01U16V1KX-GP"
			(at -2.8321 -1.7399 90)
			(unlocked yes)
			(layer "F.Fab")
			(hide yes)
			(effects
				(font
					(size 1.016 1.016)
					(thickness 0.1524)
				)
			)
		)
		(property "Device Type" "C0201H13"
			(at -2.8321 -3.2639 90)
			(unlocked yes)
			(layer "F.Fab")
			(hide yes)
			(effects
				(font
					(size 1.016 1.016)
					(thickness 0.1524)
				)
			)
		)
		(duplicate_pad_numbers_are_jumpers no)
		(fp_rect
			(start -0.2794 0.6477)
			(end 0.2794 -0.6477)
			(stroke
				(width 0)
				(type default)
			)
			(fill no)
			(layer "F.CrtYd")
		)
		(fp_rect
			(start -0.2794 0.6477)
			(end 0.2794 -0.6477)
			(stroke
				(width 0)
				(type default)
			)
			(fill no)
			(layer "F.Fab")
		)
		(pad "1" smd custom
			(at 0 -0.2794 90)
			(size 0.0762 0.0762)
			(layers "F.Cu" "F.Mask" "F.Paste")
			(net "SAS_HDD_RX_P16")
			(options
				(clearance outline)
				(anchor circle)
			)
			(primitives
				(gr_poly
					(pts
						(arc
							(start 0.1524 -0.127)
							(mid 0.137521 -0.162921)
							(end 0.1016 -0.1778)
						)
						(arc
							(start -0.1016 -0.1778)
							(mid -0.137521 -0.162921)
							(end -0.1524 -0.127)
						)
						(arc
							(start -0.1524 0.127)
							(mid -0.137521 0.162921)
							(end -0.1016 0.1778)
						)
						(arc
							(start 0.1016 0.1778)
							(mid 0.137521 0.162921)
							(end 0.1524 0.127)
						)
					)
					(width 0)
					(fill yes)
				)
			)
		)
		(pad "2" smd custom
			(at 0 0.2794 90)
			(size 0.0762 0.0762)
			(layers "F.Cu" "F.Mask" "F.Paste")
			(net "PHY_SCC_B_TO_DRV_B_16_DP")
			(options
				(clearance outline)
				(anchor circle)
			)
			(primitives
				(gr_poly
					(pts
						(arc
							(start 0.1524 -0.127)
							(mid 0.137521 -0.162921)
							(end 0.1016 -0.1778)
						)
						(arc
							(start -0.1016 -0.1778)
							(mid -0.137521 -0.162921)
							(end -0.1524 -0.127)
						)
						(arc
							(start -0.1524 0.127)
							(mid -0.137521 0.162921)
							(end -0.1016 0.1778)
						)
						(arc
							(start 0.1016 0.1778)
							(mid 0.137521 0.162921)
							(end 0.1524 0.127)
						)
					)
					(width 0)
					(fill yes)
				)
			)
		)
	)
)
